# T6G (Grand Teton) — schematic netlist excerpt (pin names and nets, part order shuffled) for the footprints in the layout excerpt that follows; sources: Cadence DE-HDL packaged netlist, KiCad conversion of 04192023_DAF0TMB3IC0_F0TG_MB_C_brd_V02_OCP.brd

PC473_1  Q_CAP  0.1UF 25V 10% X7R  pkg 0402  page 194 : A = PVDDCR_CPU0_P0_VCCS ; B = GND
R1519  Q_RES  0 5% EMPTY  pkg 0402LF  page 136 : A = OCP_V3_1_P3V3_R3_PWRGD ; B = OCP_V3_1_P3V3_PWRGD

(kicad_pcb
	(version 20260206)
	(generator "pcbnew")
	(generator_version "10.0")
	(general
		(thickness 1.6)
		(legacy_teardrops no)
	)
	(paper "A4")
	(title_block
		(title "04192023_DAF0TMB3IC0_F0TG_MB_C_brd_V02_OCP.brd")
		(comment 1 "Grand Teton / footprints 2860-2861 of 8354")
	)
	(layers
		(0 "F.Cu" signal "TOP")
		(4 "In1.Cu" signal "GND")
		(6 "In2.Cu" signal "IN1")
		(8 "In3.Cu" signal "GND1")
		(10 "In4.Cu" signal "IN2")
		(12 "In5.Cu" signal "GND2")
		(14 "In6.Cu" signal "IN3")
		(16 "In7.Cu" signal "GND3")
		(18 "In8.Cu" signal "VCC")
		(20 "In9.Cu" signal "VCC1")
		(22 "In10.Cu" signal "GND4")
		(24 "In11.Cu" signal "IN4")
		(26 "In12.Cu" signal "GND5")
		(28 "In13.Cu" signal "IN5")
		(30 "In14.Cu" signal "GND6")
		(32 "In15.Cu" signal "IN6")
		(34 "In16.Cu" signal "GND7")
		(2 "B.Cu" signal "BOTTOM")
		(9 "F.Adhes" user "F.Adhesive")
		(11 "B.Adhes" user "B.Adhesive")
		(13 "F.Paste" user "Package Geometry/Pastemask Top")
		(15 "B.Paste" user "Package Geometry/Pastemask Bottom")
		(5 "F.SilkS" user "Ref Des/Silkscreen Top")
		(7 "B.SilkS" user "Ref Des/Silkscreen Bottom")
		(1 "F.Mask" user "Board Geometry/Soldermask Top")
		(3 "B.Mask" user "Board Geometry/Soldermask Bottom")
		(17 "Dwgs.User" user "User.Drawings")
		(19 "Cmts.User" user "User.Comments")
		(21 "Eco1.User" user "User.Eco1")
		(23 "Eco2.User" user "User.Eco2")
		(25 "Edge.Cuts" user "Board Geometry/Outline")
		(27 "Margin" user)
		(31 "F.CrtYd" user "Package Geometry/Place Bound Top")
		(29 "B.CrtYd" user "Package Geometry/Place Bound Bottom")
		(35 "F.Fab" user "Ref Des/Assembly Top")
		(33 "B.Fab" user "Ref Des/Assembly Bottom")
	)
	(footprint ""
		(layer "F.Cu")
		(at 220.26626 -98.11004 90)
		(property "Reference" "R1519"
			(at 0 0 90)
			(layer "F.SilkS")
			(hide yes)
			(effects
				(font
					(size 1.27 1.27)
				)
			)
		)
		(property "Value" ""
			(at 0 0 90)
			(layer "F.Fab")
			(effects
				(font
					(size 1.27 1.27)
				)
			)
		)
		(duplicate_pad_numbers_are_jumpers no)
		(fp_line
			(start 0.7874 -0.4064)
			(end 0.7874 0.4064)
			(stroke
				(width 0.1524)
				(type default)
			)
			(layer "F.SilkS")
		)
		(fp_line
			(start -0.7874 -0.4064)
			(end 0.7874 -0.4064)
			(stroke
				(width 0.1524)
				(type default)
			)
			(layer "F.SilkS")
		)
		(fp_line
			(start 0.7874 0.4064)
			(end -0.7874 0.4064)
			(stroke
				(width 0.1524)
				(type default)
			)
			(layer "F.SilkS")
		)
		(fp_line
			(start -0.7874 0.4064)
			(end -0.7874 -0.4064)
			(stroke
				(width 0.1524)
				(type default)
			)
			(layer "F.SilkS")
		)
		(fp_line
			(start -0.12065 -0.305054)
			(end -0.12065 -0.2794)
			(stroke
				(width 0.1)
				(type default)
			)
			(layer "F.Fab")
		)
		(fp_line
			(start -0.67945 -0.305054)
			(end -0.12065 -0.305054)
			(stroke
				(width 0.1)
				(type default)
			)
			(layer "F.Fab")
		)
		(fp_line
			(start 0.67945 -0.3048)
			(end 0.67945 0.3048)
			(stroke
				(width 0.1)
				(type default)
			)
			(layer "F.Fab")
		)
		(fp_line
			(start 0.12065 -0.3048)
			(end 0.67945 -0.3048)
			(stroke
				(width 0.1)
				(type default)
			)
			(layer "F.Fab")
		)
		(fp_line
			(start 0.12065 -0.2794)
			(end 0.12065 -0.3048)
			(stroke
				(width 0.1)
				(type default)
			)
			(layer "F.Fab")
		)
		(fp_line
			(start -0.12065 -0.2794)
			(end 0.12065 -0.2794)
			(stroke
				(width 0.1)
				(type default)
			)
			(layer "F.Fab")
		)
		(fp_line
			(start 0.120396 0.2794)
			(end -0.12065 0.2794)
			(stroke
				(width 0.1)
				(type default)
			)
			(layer "F.Fab")
		)
		(fp_line
			(start -0.12065 0.2794)
			(end -0.12065 0.3048)
			(stroke
				(width 0.1)
				(type default)
			)
			(layer "F.Fab")
		)
		(fp_line
			(start 0.67945 0.3048)
			(end 0.120396 0.3048)
			(stroke
				(width 0.1)
				(type default)
			)
			(layer "F.Fab")
		)
		(fp_line
			(start 0.120396 0.3048)
			(end 0.120396 0.2794)
			(stroke
				(width 0.1)
				(type default)
			)
			(layer "F.Fab")
		)
		(fp_line
			(start -0.12065 0.3048)
			(end -0.67945 0.3048)
			(stroke
				(width 0.1)
				(type default)
			)
			(layer "F.Fab")
		)
		(fp_line
			(start -0.67945 0.3048)
			(end -0.67945 -0.305054)
			(stroke
				(width 0.1)
				(type default)
			)
			(layer "F.Fab")
		)
		(pad "1" smd circle
			(at -0.40005 0 90)
			(size 0 0)
			(layers "F.Cu" "F.Mask" "F.Paste")
			(net "OCP_V3_1_P3V3_R3_PWRGD")
		)
		(pad "2" smd circle
			(at 0.40005 0 90)
			(size 0 0)
			(layers "F.Cu" "F.Mask" "F.Paste")
			(net "OCP_V3_1_P3V3_PWRGD")
		)
	)
	(footprint ""
		(layer "F.Cu")
		(at 367.007902 -172.913802 -90)
		(property "Reference" "PC473_1"
			(at 0 0 270)
			(layer "F.SilkS")
			(hide yes)
			(effects
				(font
					(size 1.27 1.27)
				)
			)
		)
		(property "Value" ""
			(at 0 0 270)
			(layer "F.Fab")
			(effects
				(font
					(size 1.27 1.27)
				)
			)
		)
		(duplicate_pad_numbers_are_jumpers no)
		(fp_line
			(start -0.7874 0.4064)
			(end -0.7874 -0.4064)
			(stroke
				(width 0.1524)
				(type default)
			)
			(layer "F.SilkS")
		)
		(fp_line
			(start 0.7874 0.4064)
			(end -0.7874 0.4064)
			(stroke
				(width 0.1524)
				(type default)
			)
			(layer "F.SilkS")
		)
		(fp_line
			(start -0.7874 -0.4064)
			(end 0.7874 -0.4064)
			(stroke
				(width 0.1524)
				(type default)
			)
			(layer "F.SilkS")
		)
		(fp_line
			(start 0.7874 -0.4064)
			(end 0.7874 0.4064)
			(stroke
				(width 0.1524)
				(type default)
			)
			(layer "F.SilkS")
		)
		(fp_line
			(start -0.67945 0.3048)
			(end -0.67945 -0.305054)
			(stroke
				(width 0.1)
				(type default)
			)
			(layer "F.Fab")
		)
		(fp_line
			(start -0.12065 0.3048)
			(end -0.67945 0.3048)
			(stroke
				(width 0.1)
				(type default)
			)
			(layer "F.Fab")
		)
		(fp_line
			(start 0.120396 0.3048)
			(end 0.120396 0.2794)
			(stroke
				(width 0.1)
				(type default)
			)
			(layer "F.Fab")
		)
		(fp_line
			(start 0.67945 0.3048)
			(end 0.120396 0.3048)
			(stroke
				(width 0.1)
				(type default)
			)
			(layer "F.Fab")
		)
		(fp_line
			(start -0.12065 0.2794)
			(end -0.12065 0.3048)
			(stroke
				(width 0.1)
				(type default)
			)
			(layer "F.Fab")
		)
		(fp_line
			(start 0.120396 0.2794)
			(end -0.12065 0.2794)
			(stroke
				(width 0.1)
				(type default)
			)
			(layer "F.Fab")
		)
		(fp_line
			(start -0.12065 -0.2794)
			(end 0.12065 -0.2794)
			(stroke
				(width 0.1)
				(type default)
			)
			(layer "F.Fab")
		)
		(fp_line
			(start 0.12065 -0.2794)
			(end 0.12065 -0.3048)
			(stroke
				(width 0.1)
				(type default)
			)
			(layer "F.Fab")
		)
		(fp_line
			(start 0.12065 -0.3048)
			(end 0.67945 -0.3048)
			(stroke
				(width 0.1)
				(type default)
			)
			(layer "F.Fab")
		)
		(fp_line
			(start 0.67945 -0.3048)
			(end 0.67945 0.3048)
			(stroke
				(width 0.1)
				(type default)
			)
			(layer "F.Fab")
		)
		(fp_line
			(start -0.67945 -0.305054)
			(end -0.12065 -0.305054)
			(stroke
				(width 0.1)
				(type default)
			)
			(layer "F.Fab")
		)
		(fp_line
			(start -0.12065 -0.305054)
			(end -0.12065 -0.2794)
			(stroke
				(width 0.1)
				(type default)
			)
			(layer "F.Fab")
		)
		(pad "1" smd circle
			(at -0.40005 0 270)
			(size 0 0)
			(layers "F.Cu" "F.Mask" "F.Paste")
			(net "PVDDCR_CPU0_P0_VCCS")
		)
		(pad "2" smd circle
			(at 0.40005 0 270)
			(size 0 0)
			(layers "F.Cu" "F.Mask" "F.Paste")
			(net "GND")
		)
	)
)
